(kicad_pcb
	(version 20260206)
	(generator "pcbnew")
	(generator_version "10.0")
	(general
		(thickness 1.6)
		(legacy_teardrops no)
	)
	(paper "A4")
	(title_block
		(title "fcb — Lightning_FCB_BRD.brd")
		(comment 1 "Lightning (Wiwynn / Facebook NVMe JBOF) / footprints 489-495 of 495")
	)
	(layers
		(0 "F.Cu" signal "TOP")
		(4 "In1.Cu" signal "L2GND")
		(6 "In2.Cu" signal "L3VCC")
		(2 "B.Cu" signal "BOTTOM")
		(9 "F.Adhes" user "F.Adhesive")
		(11 "B.Adhes" user "B.Adhesive")
		(13 "F.Paste" user "Package Geometry/Pastemask Top")
		(15 "B.Paste" user "Package Geometry/Pastemask Bottom")
		(5 "F.SilkS" user "Ref Des/Silkscreen Top")
		(7 "B.SilkS" user "Ref Des/Silkscreen Bottom")
		(1 "F.Mask" user "Board Geometry/Soldermask Top")
		(3 "B.Mask" user "Board Geometry/Soldermask Bottom")
		(17 "Dwgs.User" user "User.Drawings")
		(19 "Cmts.User" user "User.Comments")
		(21 "Eco1.User" user "User.Eco1")
		(23 "Eco2.User" user "User.Eco2")
		(25 "Edge.Cuts" user "Board Geometry/Outline")
		(27 "Margin" user)
		(31 "F.CrtYd" user "Package Geometry/Place Bound Top")
		(29 "B.CrtYd" user "Package Geometry/Place Bound Bottom")
		(35 "F.Fab" user "Ref Des/Assembly Top")
		(33 "B.Fab" user "Ref Des/Assembly Bottom")
	)
	(footprint ""
		(layer "F.Cu")
		(at 22.860762 -15.621508 90)
		(property "Reference" "R77"
			(at 0 0 90)
			(layer "F.SilkS")
			(hide yes)
			(effects
				(font
					(size 1.27 1.27)
				)
			)
		)
		(property "Value" "10KR2F-2-GP"
			(at 0.064008 -3.993896 90)
			(unlocked yes)
			(layer "F.Fab")
			(hide yes)
			(effects
				(font
					(size 1.016 1.016)
					(thickness 0.1524)
				)
			)
		)
		(property "Device Type" "R402H16"
			(at 0.064008 -5.517896 90)
			(unlocked yes)
			(layer "F.Fab")
			(hide yes)
			(effects
				(font
					(size 1.016 1.016)
					(thickness 0.1524)
				)
			)
		)
		(duplicate_pad_numbers_are_jumpers no)
		(fp_line
			(start 0.508 -0.9398)
			(end -0.508 -0.9398)
			(stroke
				(width 0.1524)
				(type default)
			)
			(layer "F.SilkS")
		)
		(fp_line
			(start -0.508 -0.9398)
			(end -0.508 0.9398)
			(stroke
				(width 0.1524)
				(type default)
			)
			(layer "F.SilkS")
		)
		(fp_rect
			(start -0.508 0.9398)
			(end 0.508 -0.9398)
			(stroke
				(width 0)
				(type default)
			)
			(fill no)
			(layer "F.CrtYd")
		)
		(fp_rect
			(start -0.508 0.9398)
			(end 0.508 -0.9398)
			(stroke
				(width 0)
				(type default)
			)
			(fill no)
			(layer "F.Fab")
		)
		(pad "1" smd custom
			(at 0 -0.4445 90)
			(size 0.1397 0.1397)
			(layers "F.Cu" "F.Mask" "F.Paste")
			(net "FANIN_11")
			(options
				(clearance outline)
				(anchor circle)
			)
			(primitives
				(gr_poly
					(pts
						(arc
							(start -0.1778 -0.2794)
							(mid -0.249642 -0.249642)
							(end -0.2794 -0.1778)
						)
						(arc
							(start -0.2794 0.1778)
							(mid -0.249642 0.249642)
							(end -0.1778 0.2794)
						)
						(arc
							(start 0.1778 0.2794)
							(mid 0.249642 0.249642)
							(end 0.2794 0.1778)
						)
						(arc
							(start 0.2794 -0.1778)
							(mid 0.249642 -0.249642)
							(end 0.1778 -0.2794)
						)
					)
					(width 0)
					(fill yes)
				)
			)
		)
		(pad "2" smd custom
			(at 0 0.4445 90)
			(size 0.1397 0.1397)
			(layers "F.Cu" "F.Mask" "F.Paste")
			(net "GND")
			(options
				(clearance outline)
				(anchor circle)
			)
			(primitives
				(gr_poly
					(pts
						(arc
							(start -0.1778 -0.2794)
							(mid -0.249642 -0.249642)
							(end -0.2794 -0.1778)
						)
						(arc
							(start -0.2794 0.1778)
							(mid -0.249642 0.249642)
							(end -0.1778 0.2794)
						)
						(arc
							(start 0.1778 0.2794)
							(mid 0.249642 0.249642)
							(end 0.2794 0.1778)
						)
						(arc
							(start 0.2794 -0.1778)
							(mid 0.249642 -0.249642)
							(end 0.1778 -0.2794)
						)
					)
					(width 0)
					(fill yes)
				)
			)
		)
	)
	(footprint ""
		(layer "F.Cu")
		(at 26.289 -151.3078)
		(property "Reference" "C5"
			(at 0 0 0)
			(layer "F.SilkS")
			(hide yes)
			(effects
				(font
					(size 1.27 1.27)
				)
			)
		)
		(property "Value" "SCD1U16V2KX-3GP"
			(at 1.1811 -2.7051 0)
			(unlocked yes)
			(layer "F.Fab")
			(hide yes)
			(effects
				(font
					(size 1.016 1.016)
					(thickness 0.1524)
				)
			)
		)
		(property "Device Type" "C402H22"
			(at 1.1811 -4.2291 0)
			(unlocked yes)
			(layer "F.Fab")
			(hide yes)
			(effects
				(font
					(size 1.016 1.016)
					(thickness 0.1524)
				)
			)
		)
		(duplicate_pad_numbers_are_jumpers no)
		(fp_rect
			(start -0.4318 0.9525)
			(end 0.4318 -0.9525)
			(stroke
				(width 0)
				(type default)
			)
			(fill no)
			(layer "F.CrtYd")
		)
		(fp_rect
			(start -0.4318 0.9525)
			(end 0.4318 -0.9525)
			(stroke
				(width 0)
				(type default)
			)
			(fill no)
			(layer "F.Fab")
		)
		(pad "1" smd custom
			(at 0 -0.4445)
			(size 0.1524 0.1524)
			(layers "F.Cu" "F.Mask" "F.Paste")
			(net "NCT7904_VREF")
			(options
				(clearance outline)
				(anchor circle)
			)
			(primitives
				(gr_poly
					(pts
						(arc
							(start 0.3048 -0.2032)
							(mid 0.275042 -0.275042)
							(end 0.2032 -0.3048)
						)
						(arc
							(start -0.2032 -0.3048)
							(mid -0.275042 -0.275042)
							(end -0.3048 -0.2032)
						)
						(arc
							(start -0.3048 0.2032)
							(mid -0.275042 0.275042)
							(end -0.2032 0.3048)
						)
						(arc
							(start 0.2032 0.3048)
							(mid 0.275042 0.275042)
							(end 0.3048 0.2032)
						)
					)
					(width 0)
					(fill yes)
				)
			)
		)
		(pad "2" smd custom
			(at 0 0.4445)
			(size 0.1524 0.1524)
			(layers "F.Cu" "F.Mask" "F.Paste")
			(net "GND")
			(options
				(clearance outline)
				(anchor circle)
			)
			(primitives
				(gr_poly
					(pts
						(arc
							(start 0.3048 -0.2032)
							(mid 0.275042 -0.275042)
							(end 0.2032 -0.3048)
						)
						(arc
							(start -0.2032 -0.3048)
							(mid -0.275042 -0.275042)
							(end -0.3048 -0.2032)
						)
						(arc
							(start -0.3048 0.2032)
							(mid -0.275042 0.275042)
							(end -0.2032 0.3048)
						)
						(arc
							(start 0.2032 0.3048)
							(mid 0.275042 0.275042)
							(end 0.3048 0.2032)
						)
					)
					(width 0)
					(fill yes)
				)
			)
		)
	)
	(footprint ""
		(layer "B.Cu")
		(at 40.999918 -463.049874 90)
		(property "Reference" "H11"
			(at 0 0 90)
			(layer "B.SilkS")
			(hide yes)
			(effects
				(font
					(size 1.27 1.27)
				)
				(justify mirror)
			)
		)
		(property "Value" "STF375R199H50-GP"
			(at 6.124702 -0.033274 90)
			(unlocked yes)
			(layer "B.Fab")
			(hide yes)
			(effects
				(font
					(size 1.016 1.016)
					(thickness 0.1524)
				)
				(justify mirror)
			)
		)
		(property "Device Type" "STF375R199H50"
			(at 6.124702 -1.557274 90)
			(unlocked yes)
			(layer "B.Fab")
			(hide yes)
			(effects
				(font
					(size 1.016 1.016)
					(thickness 0.1524)
				)
				(justify mirror)
			)
		)
		(duplicate_pad_numbers_are_jumpers no)
		(fp_circle
			(center 0 0)
			(end 0 5.1181)
			(stroke
				(width 0.3048)
				(type default)
			)
			(fill no)
			(layer "B.SilkS")
		)
		(fp_poly
			(pts
				(arc
					(start 0 4.0005)
					(mid 0 -4.0005)
					(end 0 4.0005)
				)
			)
			(stroke
				(width 0)
				(type default)
			)
			(fill no)
			(layer "B.CrtYd")
		)
		(fp_poly
			(pts
				(arc
					(start -5.2705 0.00254)
					(mid 5.270501 0)
					(end -5.2705 -0.00254)
				)
				(arc
					(start -4.0005 -0.00254)
					(mid 4.000501 0)
					(end -4.0005 0.00254)
				)
			)
			(stroke
				(width 0)
				(type default)
			)
			(fill no)
			(layer "B.CrtYd")
		)
		(fp_poly
			(pts
				(arc
					(start 0 5.2705)
					(mid 0 -5.2705)
					(end 0 5.2705)
				)
			)
			(stroke
				(width 0)
				(type default)
			)
			(fill no)
			(layer "F.CrtYd")
		)
		(fp_poly
			(pts
				(arc
					(start 0 5.2705)
					(mid 0 -5.2705)
					(end 0 5.2705)
				)
			)
			(stroke
				(width 0)
				(type default)
			)
			(fill no)
			(layer "B.Fab")
		)
		(fp_poly
			(pts
				(arc
					(start 0 5.2705)
					(mid 0 -5.2705)
					(end 0 5.2705)
				)
			)
			(stroke
				(width 0)
				(type default)
			)
			(fill no)
			(layer "F.Fab")
		)
		(pad "1" thru_hole circle
			(at 0 0 270)
			(size 9.525 9.525)
			(drill 5.0546)
			(layers "*.Cu" "*.Mask")
			(remove_unused_layers no)
			(net "GND")
			(clearance -1.7272)
			(padstack
				(mode front_inner_back)
				(layer "Inner"
					(shape circle)
					(size 5.461 5.461)
					(clearance 0.3048)
				)
				(layer "B.Cu"
					(shape circle)
					(size 9.525 9.525)
					(thermal_gap 0.3048)
					(clearance -1.7272)
				)
			)
		)
	)
	(footprint ""
		(layer "B.Cu")
		(at 40.999918 -443.95009 90)
		(property "Reference" "H12"
			(at 0 0 90)
			(layer "B.SilkS")
			(hide yes)
			(effects
				(font
					(size 1.27 1.27)
				)
				(justify mirror)
			)
		)
		(property "Value" "STF375R199H50-GP"
			(at 6.124702 -0.033274 90)
			(unlocked yes)
			(layer "B.Fab")
			(hide yes)
			(effects
				(font
					(size 1.016 1.016)
					(thickness 0.1524)
				)
				(justify mirror)
			)
		)
		(property "Device Type" "STF375R199H50"
			(at 6.124702 -1.557274 90)
			(unlocked yes)
			(layer "B.Fab")
			(hide yes)
			(effects
				(font
					(size 1.016 1.016)
					(thickness 0.1524)
				)
				(justify mirror)
			)
		)
		(duplicate_pad_numbers_are_jumpers no)
		(fp_circle
			(center 0 0)
			(end 0 5.1181)
			(stroke
				(width 0.3048)
				(type default)
			)
			(fill no)
			(layer "B.SilkS")
		)
		(fp_poly
			(pts
				(arc
					(start 0 4.0005)
					(mid 0 -4.0005)
					(end 0 4.0005)
				)
			)
			(stroke
				(width 0)
				(type default)
			)
			(fill no)
			(layer "B.CrtYd")
		)
		(fp_poly
			(pts
				(arc
					(start -5.2705 0.00254)
					(mid 5.270501 0)
					(end -5.2705 -0.00254)
				)
				(arc
					(start -4.0005 -0.00254)
					(mid 4.000501 0)
					(end -4.0005 0.00254)
				)
			)
			(stroke
				(width 0)
				(type default)
			)
			(fill no)
			(layer "B.CrtYd")
		)
		(fp_poly
			(pts
				(arc
					(start 0 5.2705)
					(mid 0 -5.2705)
					(end 0 5.2705)
				)
			)
			(stroke
				(width 0)
				(type default)
			)
			(fill no)
			(layer "F.CrtYd")
		)
		(fp_poly
			(pts
				(arc
					(start 0 5.2705)
					(mid 0 -5.2705)
					(end 0 5.2705)
				)
			)
			(stroke
				(width 0)
				(type default)
			)
			(fill no)
			(layer "B.Fab")
		)
		(fp_poly
			(pts
				(arc
					(start 0 5.2705)
					(mid 0 -5.2705)
					(end 0 5.2705)
				)
			)
			(stroke
				(width 0)
				(type default)
			)
			(fill no)
			(layer "F.Fab")
		)
		(pad "1" thru_hole circle
			(at 0 0 270)
			(size 9.525 9.525)
			(drill 5.0546)
			(layers "*.Cu" "*.Mask")
			(remove_unused_layers no)
			(net "GND")
			(clearance -1.7272)
			(padstack
				(mode front_inner_back)
				(layer "Inner"
					(shape circle)
					(size 5.461 5.461)
					(clearance 0.3048)
				)
				(layer "B.Cu"
					(shape circle)
					(size 9.525 9.525)
					(thermal_gap 0.3048)
					(clearance -1.7272)
				)
			)
		)
	)
	(footprint ""
		(layer "B.Cu")
		(at 45.449998 -337.49996 90)
		(property "Reference" "H13"
			(at 0 0 90)
			(layer "B.SilkS")
			(hide yes)
			(effects
				(font
					(size 1.27 1.27)
				)
				(justify mirror)
			)
		)
		(property "Value" "STF375R199H50-GP"
			(at 6.124702 -0.033274 90)
			(unlocked yes)
			(layer "B.Fab")
			(hide yes)
			(effects
				(font
					(size 1.016 1.016)
					(thickness 0.1524)
				)
				(justify mirror)
			)
		)
		(property "Device Type" "STF375R199H50"
			(at 6.124702 -1.557274 90)
			(unlocked yes)
			(layer "B.Fab")
			(hide yes)
			(effects
				(font
					(size 1.016 1.016)
					(thickness 0.1524)
				)
				(justify mirror)
			)
		)
		(duplicate_pad_numbers_are_jumpers no)
		(fp_circle
			(center 0 0)
			(end 0 5.1181)
			(stroke
				(width 0.3048)
				(type default)
			)
			(fill no)
			(layer "B.SilkS")
		)
		(fp_poly
			(pts
				(arc
					(start -4.0005 0)
					(mid 4.0005 0)
					(end -4.0005 0)
				)
			)
			(stroke
				(width 0)
				(type default)
			)
			(fill no)
			(layer "B.CrtYd")
		)
		(fp_poly
			(pts
				(arc
					(start -5.2705 0.00254)
					(mid 5.270501 0)
					(end -5.2705 -0.00254)
				)
				(arc
					(start -4.0005 -0.00254)
					(mid 4.000501 0)
					(end -4.0005 0.00254)
				)
			)
			(stroke
				(width 0)
				(type default)
			)
			(fill no)
			(layer "B.CrtYd")
		)
		(fp_poly
			(pts
				(arc
					(start -5.2705 0)
					(mid 5.2705 0)
					(end -5.2705 0)
				)
			)
			(stroke
				(width 0)
				(type default)
			)
			(fill no)
			(layer "F.CrtYd")
		)
		(fp_poly
			(pts
				(arc
					(start -5.2705 0)
					(mid 5.2705 0)
					(end -5.2705 0)
				)
			)
			(stroke
				(width 0)
				(type default)
			)
			(fill no)
			(layer "B.Fab")
		)
		(fp_poly
			(pts
				(arc
					(start -5.2705 0)
					(mid 5.2705 0)
					(end -5.2705 0)
				)
			)
			(stroke
				(width 0)
				(type default)
			)
			(fill no)
			(layer "F.Fab")
		)
		(pad "1" thru_hole circle
			(at 0 0 270)
			(size 9.525 9.525)
			(drill 5.0546)
			(layers "*.Cu" "*.Mask")
			(remove_unused_layers no)
			(net "GND")
			(clearance -1.7272)
			(padstack
				(mode front_inner_back)
				(layer "Inner"
					(shape circle)
					(size 5.461 5.461)
					(clearance 0.3048)
				)
				(layer "B.Cu"
					(shape circle)
					(size 9.525 9.525)
					(thermal_gap 0.3048)
					(clearance -1.7272)
				)
			)
		)
	)
	(footprint ""
		(layer "B.Cu")
		(at 24.500078 -463.049874 90)
		(property "Reference" "H9"
			(at 0 0 90)
			(layer "B.SilkS")
			(hide yes)
			(effects
				(font
					(size 1.27 1.27)
				)
				(justify mirror)
			)
		)
		(property "Value" "STF375R199H50-GP"
			(at 6.124702 -0.033274 90)
			(unlocked yes)
			(layer "B.Fab")
			(hide yes)
			(effects
				(font
					(size 1.016 1.016)
					(thickness 0.1524)
				)
				(justify mirror)
			)
		)
		(property "Device Type" "STF375R199H50"
			(at 6.124702 -1.557274 90)
			(unlocked yes)
			(layer "B.Fab")
			(hide yes)
			(effects
				(font
					(size 1.016 1.016)
					(thickness 0.1524)
				)
				(justify mirror)
			)
		)
		(duplicate_pad_numbers_are_jumpers no)
		(fp_circle
			(center 0 0)
			(end 0 5.1181)
			(stroke
				(width 0.3048)
				(type default)
			)
			(fill no)
			(layer "B.SilkS")
		)
		(fp_poly
			(pts
				(arc
					(start 0 4.0005)
					(mid 0 -4.0005)
					(end 0 4.0005)
				)
			)
			(stroke
				(width 0)
				(type default)
			)
			(fill no)
			(layer "B.CrtYd")
		)
		(fp_poly
			(pts
				(arc
					(start -5.2705 0.00254)
					(mid 5.270501 0)
					(end -5.2705 -0.00254)
				)
				(arc
					(start -4.0005 -0.00254)
					(mid 4.000501 0)
					(end -4.0005 0.00254)
				)
			)
			(stroke
				(width 0)
				(type default)
			)
			(fill no)
			(layer "B.CrtYd")
		)
		(fp_poly
			(pts
				(arc
					(start 0 5.2705)
					(mid 0 -5.2705)
					(end 0 5.2705)
				)
			)
			(stroke
				(width 0)
				(type default)
			)
			(fill no)
			(layer "F.CrtYd")
		)
		(fp_poly
			(pts
				(arc
					(start 0 5.2705)
					(mid 0 -5.2705)
					(end 0 5.2705)
				)
			)
			(stroke
				(width 0)
				(type default)
			)
			(fill no)
			(layer "B.Fab")
		)
		(fp_poly
			(pts
				(arc
					(start 0 5.2705)
					(mid 0 -5.2705)
					(end 0 5.2705)
				)
			)
			(stroke
				(width 0)
				(type default)
			)
			(fill no)
			(layer "F.Fab")
		)
		(pad "1" thru_hole circle
			(at 0 0 270)
			(size 9.525 9.525)
			(drill 5.0546)
			(layers "*.Cu" "*.Mask")
			(remove_unused_layers no)
			(net "P12V_AUX")
			(clearance -1.7272)
			(padstack
				(mode front_inner_back)
				(layer "Inner"
					(shape circle)
					(size 5.461 5.461)
					(clearance 0.3048)
				)
				(layer "B.Cu"
					(shape circle)
					(size 9.525 9.525)
					(thermal_gap 0.3048)
					(clearance -1.7272)
				)
			)
		)
	)
	(footprint ""
		(layer "B.Cu")
		(at 24.500078 -443.95009 90)
		(property "Reference" "H10"
			(at 0 0 90)
			(layer "B.SilkS")
			(hide yes)
			(effects
				(font
					(size 1.27 1.27)
				)
				(justify mirror)
			)
		)
		(property "Value" "STF375R199H50-GP"
			(at 6.124702 -0.033274 90)
			(unlocked yes)
			(layer "B.Fab")
			(hide yes)
			(effects
				(font
					(size 1.016 1.016)
					(thickness 0.1524)
				)
				(justify mirror)
			)
		)
		(property "Device Type" "STF375R199H50"
			(at 6.124702 -1.557274 90)
			(unlocked yes)
			(layer "B.Fab")
			(hide yes)
			(effects
				(font
					(size 1.016 1.016)
					(thickness 0.1524)
				)
				(justify mirror)
			)
		)
		(duplicate_pad_numbers_are_jumpers no)
		(fp_circle
			(center 0 0)
			(end 0 5.1181)
			(stroke
				(width 0.3048)
				(type default)
			)
			(fill no)
			(layer "B.SilkS")
		)
		(fp_poly
			(pts
				(arc
					(start 0 4.0005)
					(mid 0 -4.0005)
					(end 0 4.0005)
				)
			)
			(stroke
				(width 0)
				(type default)
			)
			(fill no)
			(layer "B.CrtYd")
		)
		(fp_poly
			(pts
				(arc
					(start -5.2705 0.00254)
					(mid 5.270501 0)
					(end -5.2705 -0.00254)
				)
				(arc
					(start -4.0005 -0.00254)
					(mid 4.000501 0)
					(end -4.0005 0.00254)
				)
			)
			(stroke
				(width 0)
				(type default)
			)
			(fill no)
			(layer "B.CrtYd")
		)
		(fp_poly
			(pts
				(arc
					(start 0 5.2705)
					(mid 0 -5.2705)
					(end 0 5.2705)
				)
			)
			(stroke
				(width 0)
				(type default)
			)
			(fill no)
			(layer "F.CrtYd")
		)
		(fp_poly
			(pts
				(arc
					(start 0 5.2705)
					(mid 0 -5.2705)
					(end 0 5.2705)
				)
			)
			(stroke
				(width 0)
				(type default)
			)
			(fill no)
			(layer "B.Fab")
		)
		(fp_poly
			(pts
				(arc
					(start 0 5.2705)
					(mid 0 -5.2705)
					(end 0 5.2705)
				)
			)
			(stroke
				(width 0)
				(type default)
			)
			(fill no)
			(layer "F.Fab")
		)
		(pad "1" thru_hole circle
			(at 0 0 270)
			(size 9.525 9.525)
			(drill 5.0546)
			(layers "*.Cu" "*.Mask")
			(remove_unused_layers no)
			(net "P12V_AUX")
			(clearance -1.7272)
			(padstack
				(mode front_inner_back)
				(layer "Inner"
					(shape circle)
					(size 5.461 5.461)
					(clearance 0.3048)
				)
				(layer "B.Cu"
					(shape circle)
					(size 9.525 9.525)
					(thermal_gap 0.3048)
					(clearance -1.7272)
				)
			)
		)
	)
)
